# T6G (Grand Teton) — schematic netlist excerpt (pin names and nets, part order shuffled) for the footprints in the layout excerpt that follows; sources: Cadence DE-HDL packaged netlist, KiCad conversion of 04192023_DAF0TMB3IC0_F0TG_MB_C_brd_V02_OCP.brd

R1367  Q_RES  4.7K 5% CHIP  pkg 0201LF  page 185 : A = P1V8_CPU0_RT_1D ; B = SMB_RT_CPU0_P0_ROM_MUX_2D_R_SCL
PC339_2  Q_CAP  22UF 4V 20% X6S  pkg C0805  page 215 : A = PVDDCR_SOC_P1 ; B = GND
PR281  Q_RES  0 5% CHIP  pkg 0402LF  page 222 : A = PVDDIO_P1_VOS2 ; B = PVDDIO_P1

(kicad_pcb
	(version 20260206)
	(generator "pcbnew")
	(generator_version "10.0")
	(general
		(thickness 1.6)
		(legacy_teardrops no)
	)
	(paper "A4")
	(title_block
		(title "04192023_DAF0TMB3IC0_F0TG_MB_C_brd_V02_OCP.brd")
		(comment 1 "Grand Teton / footprints 7952-7954 of 8354")
	)
	(layers
		(0 "F.Cu" signal "TOP")
		(4 "In1.Cu" signal "GND")
		(6 "In2.Cu" signal "IN1")
		(8 "In3.Cu" signal "GND1")
		(10 "In4.Cu" signal "IN2")
		(12 "In5.Cu" signal "GND2")
		(14 "In6.Cu" signal "IN3")
		(16 "In7.Cu" signal "GND3")
		(18 "In8.Cu" signal "VCC")
		(20 "In9.Cu" signal "VCC1")
		(22 "In10.Cu" signal "GND4")
		(24 "In11.Cu" signal "IN4")
		(26 "In12.Cu" signal "GND5")
		(28 "In13.Cu" signal "IN5")
		(30 "In14.Cu" signal "GND6")
		(32 "In15.Cu" signal "IN6")
		(34 "In16.Cu" signal "GND7")
		(2 "B.Cu" signal "BOTTOM")
		(9 "F.Adhes" user "F.Adhesive")
		(11 "B.Adhes" user "B.Adhesive")
		(13 "F.Paste" user "Package Geometry/Pastemask Top")
		(15 "B.Paste" user "Package Geometry/Pastemask Bottom")
		(5 "F.SilkS" user "Ref Des/Silkscreen Top")
		(7 "B.SilkS" user "Ref Des/Silkscreen Bottom")
		(1 "F.Mask" user "Board Geometry/Soldermask Top")
		(3 "B.Mask" user "Board Geometry/Soldermask Bottom")
		(17 "Dwgs.User" user "User.Drawings")
		(19 "Cmts.User" user "User.Comments")
		(21 "Eco1.User" user "User.Eco1")
		(23 "Eco2.User" user "User.Eco2")
		(25 "Edge.Cuts" user "Board Geometry/Outline")
		(27 "Margin" user)
		(31 "F.CrtYd" user "Package Geometry/Place Bound Top")
		(29 "B.CrtYd" user "Package Geometry/Place Bound Bottom")
		(35 "F.Fab" user "Ref Des/Assembly Top")
		(33 "B.Fab" user "Ref Des/Assembly Bottom")
	)
	(footprint ""
		(layer "B.Cu")
		(at 41.525444 -349.386398 -90)
		(property "Reference" "PR281"
			(at 0 0 90)
			(layer "B.SilkS")
			(hide yes)
			(effects
				(font
					(size 1.27 1.27)
				)
				(justify mirror)
			)
		)
		(property "Value" ""
			(at 0 0 90)
			(layer "B.Fab")
			(effects
				(font
					(size 1.27 1.27)
				)
				(justify mirror)
			)
		)
		(duplicate_pad_numbers_are_jumpers no)
		(fp_line
			(start -0.7874 0.4064)
			(end 0.7874 0.4064)
			(stroke
				(width 0.1524)
				(type default)
			)
			(layer "B.SilkS")
		)
		(fp_line
			(start 0.7874 0.4064)
			(end 0.7874 -0.4064)
			(stroke
				(width 0.1524)
				(type default)
			)
			(layer "B.SilkS")
		)
		(fp_line
			(start -0.7874 -0.4064)
			(end -0.7874 0.4064)
			(stroke
				(width 0.1524)
				(type default)
			)
			(layer "B.SilkS")
		)
		(fp_line
			(start 0.7874 -0.4064)
			(end -0.7874 -0.4064)
			(stroke
				(width 0.1524)
				(type default)
			)
			(layer "B.SilkS")
		)
		(fp_line
			(start -0.67945 0.3048)
			(end -0.120396 0.3048)
			(stroke
				(width 0.1)
				(type default)
			)
			(layer "B.Fab")
		)
		(fp_line
			(start -0.120396 0.3048)
			(end -0.120396 0.2794)
			(stroke
				(width 0.1)
				(type default)
			)
			(layer "B.Fab")
		)
		(fp_line
			(start 0.12065 0.3048)
			(end 0.67945 0.3048)
			(stroke
				(width 0.1)
				(type default)
			)
			(layer "B.Fab")
		)
		(fp_line
			(start 0.67945 0.3048)
			(end 0.67945 -0.305054)
			(stroke
				(width 0.1)
				(type default)
			)
			(layer "B.Fab")
		)
		(fp_line
			(start -0.120396 0.2794)
			(end 0.12065 0.2794)
			(stroke
				(width 0.1)
				(type default)
			)
			(layer "B.Fab")
		)
		(fp_line
			(start 0.12065 0.2794)
			(end 0.12065 0.3048)
			(stroke
				(width 0.1)
				(type default)
			)
			(layer "B.Fab")
		)
		(fp_line
			(start -0.12065 -0.2794)
			(end -0.12065 -0.3048)
			(stroke
				(width 0.1)
				(type default)
			)
			(layer "B.Fab")
		)
		(fp_line
			(start 0.12065 -0.2794)
			(end -0.12065 -0.2794)
			(stroke
				(width 0.1)
				(type default)
			)
			(layer "B.Fab")
		)
		(fp_line
			(start -0.67945 -0.3048)
			(end -0.67945 0.3048)
			(stroke
				(width 0.1)
				(type default)
			)
			(layer "B.Fab")
		)
		(fp_line
			(start -0.12065 -0.3048)
			(end -0.67945 -0.3048)
			(stroke
				(width 0.1)
				(type default)
			)
			(layer "B.Fab")
		)
		(fp_line
			(start 0.12065 -0.305054)
			(end 0.12065 -0.2794)
			(stroke
				(width 0.1)
				(type default)
			)
			(layer "B.Fab")
		)
		(fp_line
			(start 0.67945 -0.305054)
			(end 0.12065 -0.305054)
			(stroke
				(width 0.1)
				(type default)
			)
			(layer "B.Fab")
		)
		(pad "1" smd circle
			(at 0.40005 0 90)
			(size 0 0)
			(layers "B.Cu" "B.Mask" "B.Paste")
			(net "PVDDIO_P1_VOS2")
		)
		(pad "2" smd circle
			(at -0.40005 0 90)
			(size 0 0)
			(layers "B.Cu" "B.Mask" "B.Paste")
			(net "PVDDIO_P1")
		)
	)
	(footprint ""
		(layer "B.Cu")
		(at 131.554474 -165.190932 90)
		(property "Reference" "PC339_2"
			(at 0 0 90)
			(layer "B.SilkS")
			(hide yes)
			(effects
				(font
					(size 1.27 1.27)
				)
				(justify mirror)
			)
		)
		(property "Value" ""
			(at 0 0 90)
			(layer "B.Fab")
			(effects
				(font
					(size 1.27 1.27)
				)
				(justify mirror)
			)
		)
		(duplicate_pad_numbers_are_jumpers no)
		(fp_line
			(start 1.524 -0.762)
			(end -1.524 -0.762)
			(stroke
				(width 0.1524)
				(type default)
			)
			(layer "B.SilkS")
		)
		(fp_line
			(start -1.524 -0.762)
			(end -1.524 0.762)
			(stroke
				(width 0.1524)
				(type default)
			)
			(layer "B.SilkS")
		)
		(fp_line
			(start 1.524 0.762)
			(end 1.524 -0.762)
			(stroke
				(width 0.1524)
				(type default)
			)
			(layer "B.SilkS")
		)
		(fp_line
			(start -1.524 0.762)
			(end 1.524 0.762)
			(stroke
				(width 0.1524)
				(type default)
			)
			(layer "B.SilkS")
		)
		(fp_line
			(start 1.1049 -0.724916)
			(end 1.1049 0.724916)
			(stroke
				(width 0.1)
				(type default)
			)
			(layer "B.Fab")
		)
		(fp_line
			(start -1.1049 -0.724916)
			(end 1.1049 -0.724916)
			(stroke
				(width 0.1)
				(type default)
			)
			(layer "B.Fab")
		)
		(fp_line
			(start 1.1049 0.724916)
			(end -1.1049 0.724916)
			(stroke
				(width 0.1)
				(type default)
			)
			(layer "B.Fab")
		)
		(fp_line
			(start -1.1049 0.724916)
			(end -1.1049 -0.724916)
			(stroke
				(width 0.1)
				(type default)
			)
			(layer "B.Fab")
		)
		(pad "1" smd rect
			(at 0.889 0 90)
			(size 1.016 1.27)
			(layers "B.Cu" "B.Mask" "B.Paste")
			(net "PVDDCR_SOC_P1")
		)
		(pad "2" smd rect
			(at -0.889 0 90)
			(size 1.016 1.27)
			(layers "B.Cu" "B.Mask" "B.Paste")
			(net "GND")
		)
	)
	(footprint ""
		(layer "B.Cu")
		(at 254.635 -340.76132 180)
		(property "Reference" "R1367"
			(at 0 0 0)
			(layer "B.SilkS")
			(hide yes)
			(effects
				(font
					(size 1.27 1.27)
				)
				(justify mirror)
			)
		)
		(property "Value" ""
			(at 0 0 0)
			(layer "B.Fab")
			(effects
				(font
					(size 1.27 1.27)
				)
				(justify mirror)
			)
		)
		(duplicate_pad_numbers_are_jumpers no)
		(fp_line
			(start 0.32512 0.175006)
			(end 0.32512 -0.175006)
			(stroke
				(width 0.1)
				(type default)
			)
			(layer "B.Fab")
		)
		(fp_line
			(start 0.32512 -0.175006)
			(end -0.32512 -0.175006)
			(stroke
				(width 0.1)
				(type default)
			)
			(layer "B.Fab")
		)
		(fp_line
			(start -0.32512 0.175006)
			(end 0.32512 0.175006)
			(stroke
				(width 0.1)
				(type default)
			)
			(layer "B.Fab")
		)
		(fp_line
			(start -0.32512 -0.175006)
			(end -0.32512 0.175006)
			(stroke
				(width 0.1)
				(type default)
			)
			(layer "B.Fab")
		)
		(pad "1" smd rect
			(at 0.2667 0)
			(size 0.3048 0.381)
			(layers "B.Cu" "B.Mask" "B.Paste")
			(net "P1V8_CPU0_RT_1D")
		)
		(pad "2" smd rect
			(at -0.2667 0 180)
			(size 0.3048 0.381)
			(layers "B.Cu" "B.Mask" "B.Paste")
			(net "SMB_RT_CPU0_P0_ROM_MUX_2D_R_SCL")
		)
	)
)
